FILE_TYPE = CONNECTIVITY;
{Allegro Design Entry HDL 17.2-2016 S081 (4005846) 1/11/2022}
"PAGE_NUMBER" = 56;
0"NC";
1"P5V_AUX\g";
2"P3V3_AUX\g";
3"PVCC2_AUX\g";
4"P3V3_LDO\g";
5"PVCC2_AUX\g";
6"P1V0_AUX\g";
7"P3V3_AUX\g";
8"PVCC2_AUX\g";
9"P12V_AUX\g";
10"GND\g";
11"GND\g";
12"GND\g";
13"GND\g";
14"GND\g";
15"GND\g";
16"GND\g";
17"GND\g";
18"GND\g";
19"GND\g";
20"PWRGD_P1V0_AUX";
21"EN_P1V0_AUX";
22"PWRGD_P1V2_AUX_R2";
23"SW_P1V0_AUX_FLT";
24"PWRGD_P1V2_AUX";
25"PWRGD_P5V_AUX";
26"EN_P1V0_AUX";
27"EN_P1V0_AUX_R";
28"SW_P1V0_AUX_BST";
29"PWRGD_P1V0_AUX_R";
30"P1V0_AUX_VCC";
31"SW_P1V0_AUX_SW";
32"P1V0_AUX_MODE";
%"UNIVERSAL_GND"
"1","(-3950,650)","0","logical_power","I10";
;
HDL_POWER"GND"
CDS_LIB"logical_power";
"A"16;
%"UNIVERSAL_GND"
"1","(-3250,-725)","0","logical_power","I14";
;
HDL_POWER"GND"
CDS_LIB"logical_power";
"A"15;
%"NB695GDZ"
"1","(-2025,150)","0","pure_quanta","I15";
;
VALUE"NB695GD-Z"
PART_TYPE"SMLF"
MATERIAL"IC"
PART_NUMBER"AL000695001"
CDS_LIB"pure_quanta"
CDS_LMAN_SYM_OUTLINE"-250,725,250,-725"
NEEDS_NO_SIZE"TRUE"
LOCATION"PU42"
$SEC"1"
CDS_SEC"1";
"3V3"
$PN"10"30;
"SW"
$PN"8"31;
"VOUT"
$PN"12"6;
"MODE"
$PN"7"32;
"C0"
$PN"4"15;
"C1"
$PN"3"30;
"LP# \B"
$PN"6"30;
"AGND"
$PN"11"14;
"BST"
$PN"9"28;
"EN"
$PN"5"27;
"PGND"
$PN"2"14;
"PG"
$PN"13"29;
"VIN"
$PN"1"23;
%"Q_CAP"
"1","(-3025,1050)","0","pure_quanta","I16";
;
MATERIAL"X7R"
PACK_TYPE"0402"
TOLERANCE"10%"
VALUE"0.1UF"
VOLTAGE"25V"
PART_NUMBER"CH4104K1B00"
CDS_LIB"pure_quanta"
SEC_TYPE"0402"
LOCATION"PC263"
SEC"1";
"B"
$PN"2"16;
"A"
$PN"1"23;
%"UNIVERSAL_GND"
"1","(-1475,-775)","0","logical_power","I17";
;
HDL_POWER"GND"
CDS_LIB"logical_power";
"A"14;
%"Q_RES"
"2","(-1350,1100)","0","pure_quanta","I18";
;
PACK_TYPE"0402LF"
PART_NUMBER"CS31002FB08"
VALUE"10K"
MATERIAL"CHIP"
WATTAGE"1/16W"
TOLERANCE"1%"
SEC_TYPE"0402LF"
CDS_LIB"pure_quanta"
LOCATION"PR500"
SEC"1";
"A"
$PN"1"7;
"B"
$PN"2"29;
%"Q_CAP"
"1","(-975,475)","0","pure_quanta","I19";
;
VOLTAGE"16V"
PACK_TYPE"0402"
VALUE"0.22UF"
TOLERANCE"10%"
MATERIAL"X7R"
PART_NUMBER"CH4223K1B00"
SEC_TYPE"0402"
CDS_LIB"pure_quanta"
LOCATION"PC264"
SEC"1";
"B"
$PN"2"31;
"A"
$PN"1"28;
%"VCCAUX15"
"1","(-5225,1650)","0","logical_power","I2";
;
HDL_POWER"P12V_AUX"
CDS_LIB"logical_power";
"A"9;
%"Q_CAP"
"1","(775,75)","0","pure_quanta","I23";
;
PACK_TYPE"0402"
MATERIAL"X7R"
PART_NUMBER"CH4104K1B00"
VALUE"0.1UF"
TOLERANCE"10%"
VOLTAGE"25V"
SEC_TYPE"0402"
CDS_LIB"pure_quanta"
LOCATION"PC266"
SEC"1";
"B"
$PN"2"13;
"A"
$PN"1"6;
%"Q_CAP"
"1","(1325,75)","0","pure_quanta","I24";
;
MATERIAL"X6S"
PACK_TYPE"0805"
TOLERANCE"20%"
VOLTAGE"4V"
VALUE"22UF"
PART_NUMBER"TMP_QCH622KMEA01"
CDS_LIB"pure_quanta"
SEC_TYPE"0805"
LOCATION"PC267"
SEC"1";
"B"
$PN"2"13;
"A"
$PN"1"6;
%"Q_CAP"
"1","(1575,75)","0","pure_quanta","I25";
;
MATERIAL"X6S"
VALUE"22UF"
TOLERANCE"20%"
PACK_TYPE"0805"
VOLTAGE"4V"
PART_NUMBER"TMP_QCH622KMEA01"
CDS_LIB"pure_quanta"
SEC_TYPE"0805"
LOCATION"PC268"
SEC"1";
"B"
$PN"2"13;
"A"
$PN"1"6;
%"UNIVERSAL_GND"
"1","(2075,-250)","0","logical_power","I27";
;
HDL_POWER"GND"
CDS_LIB"logical_power";
"A"13;
%"Q_CAP"
"1","(1825,75)","0","pure_quanta","I28";
;
MATERIAL"X6S"
VALUE"22UF"
TOLERANCE"20%"
PACK_TYPE"0805"
VOLTAGE"4V"
PART_NUMBER"TMP_QCH622KMEA01"
CDS_LIB"pure_quanta"
SEC_TYPE"0805"
LOCATION"PC269"
SEC"1";
"B"
$PN"2"13;
"A"
$PN"1"6;
%"Q_CAP"
"1","(2075,75)","0","pure_quanta","I29";
;
MATERIAL"X6S"
PART_NUMBER"TMP_QCH622KMEA01"
VALUE"22UF"
TOLERANCE"20%"
PACK_TYPE"0805"
VOLTAGE"4V"
CDS_LIB"pure_quanta"
SEC_TYPE"0805"
LOCATION"PC270"
SEC"1";
"B"
$PN"2"13;
"A"
$PN"1"6;
%"VCCAUX15"
"1","(2725,450)","0","logical_power","I30";
;
HDL_POWER"P1V0_AUX"
CDS_LIB"logical_power";
"A"6;
%"Q_INDUCTOR"
"1","(-4650,1325)","0","pure_quanta","I34";
;
PART_NUMBER"CX220TN1001"
PACK_TYPE"SMLF"
MATERIAL"IND"
VALUE"BLM18SN220TN1D/8000MA"
CDS_LIB"pure_quanta"
NEEDS_NO_SIZE"TRUE"
LOCATION"PL32"
$SEC"1"
CDS_SEC"1";
"1"
$PN"1"9;
"2"
$PN"2"23;
%"Q_INDUCTOR"
"1","(275,350)","0","pure_quanta","I37";
;
MATERIAL"IND"
PACK_TYPE"SMLF"
PART_NUMBER"CV-10B0MZ13"
DCR"DCR=9MOHM"
VALUE"1UH"
CDS_LIB"pure_quanta"
NEEDS_NO_SIZE"TRUE"
LOCATION"PL33"
$SEC"1"
CDS_SEC"1";
"1"
$PN"1"31;
"2"
$PN"2"6;
%"VCCAUX15"
"1","(-1350,1375)","0","logical_power","I38";
;
HDL_POWER"P3V3_AUX"
CDS_LIB"logical_power";
"A"7;
%"UNIVERSAL_GND"
"1","(-4025,-800)","0","logical_power","I4";
;
HDL_POWER"GND"
CDS_LIB"logical_power";
"A"12;
%"Q_CAP"
"1","(-3975,1050)","0","pure_quanta","I43";
;
TOLERANCE"10%"
VOLTAGE"25V"
VALUE"10UF"
PACK_TYPE"C0805"
PART_NUMBER"CH6104KEA00"
MATERIAL"X6S"
CDS_LIB"pure_quanta"
LOCATION"PC262"
$SEC"1"
CDS_SEC"1";
"B"
$PN"2"16;
"A"
$PN"1"23;
%"Q_CAP"
"1","(-3575,1050)","0","pure_quanta","I44";
;
TOLERANCE"10%"
VOLTAGE"25V"
VALUE"10UF"
PACK_TYPE"C0805"
PART_NUMBER"CH6104KEA00"
MATERIAL"X6S"
CDS_LIB"pure_quanta"
LOCATION"PC261"
$SEC"1"
CDS_SEC"1";
"B"
$PN"2"16;
"A"
$PN"1"23;
%"VCCAUX15"
"1","(-2375,-1325)","0","logical_power","I45";
;
HDL_POWER"PVCC2_AUX"
CDS_LIB"logical_power";
"A"8;
%"VCCAUX15"
"1","(-2375,-1650)","0","logical_power","I46";
;
HDL_POWER"PVCC2_AUX"
CDS_LIB"logical_power";
"A"5;
%"Q_RES"
"1","(-3100,-1475)","0","pure_quanta","I47";
;
PART_NUMBER"CS00002JB13"
PACK_TYPE"0402LF"
MATERIAL"CHIP"
WATTAGE"1/16W"
TOLERANCE"5%"
VALUE"0"
CDS_LIB"pure_quanta"
LOCATION"PR193"
$SEC"1"
CDS_SEC"1";
"B"
$PN"2"8;
"A"
$PN"1"2;
%"Q_RES"
"1","(-3100,-1800)","0","pure_quanta","I48";
;
PART_NUMBER"CS00002JB13"
PACK_TYPE"0402LF"
WATTAGE"1/16W"
MATERIAL"EMPTY"
TOLERANCE"5%"
VALUE"0"
CDS_LIB"pure_quanta"
LOCATION"PR205"
$SEC"1"
CDS_SEC"1";
"B"
$PN"2"5;
"A"
$PN"1"1;
%"VCCAUX15"
"1","(-3650,-1350)","0","logical_power","I49";
;
HDL_POWER"P3V3_AUX"
CDS_LIB"logical_power";
"A"2;
%"UNIVERSAL_GND"
"1","(-2950,-1100)","0","logical_power","I5";
;
HDL_POWER"GND"
CDS_LIB"logical_power";
"A"11;
%"VCCAUX15"
"1","(-3650,-1700)","0","logical_power","I50";
;
HDL_POWER"P5V_AUX"
CDS_LIB"logical_power";
"A"1;
%"Q_CAP"
"1","(-525,625)","0","pure_quanta","I51";
;
VALUE"0.001UF"
VOLTAGE"50V"
MATERIAL"EMPTY"
TOLERANCE"10%"
PACK_TYPE"C0402"
PART_NUMBER"CH30106KB19"
CDS_LIB"pure_quanta"
LOCATION"C156"
$SEC"1"
CDS_SEC"1";
"B"
$PN"2"10;
"A"
$PN"1"29;
%"UNIVERSAL_GND"
"1","(-525,425)","0","logical_power","I52";
;
HDL_POWER"GND"
CDS_LIB"logical_power";
"A"10;
%"Q_RES"
"1","(-100,825)","0","pure_quanta","I54";
;
PACK_TYPE"0402LF"
MATERIAL"CHIP"
VALUE"0"
PART_NUMBER"CS00002JB13"
WATTAGE"1/16W"
TOLERANCE"5%"
CDS_LIB"pure_quanta"
LOCATION"R277"
$SEC"1"
CDS_SEC"1";
"B"
$PN"2"20;
"A"
$PN"1"29;
%"Q_RES"
"1","(-3650,325)","0","pure_quanta","I55";
;
TOLERANCE"5%"
PACK_TYPE"0402LF"
WATTAGE"1/16W"
MATERIAL"CHIP"
VALUE"0"
PART_NUMBER"CS00002JB13"
CDS_LIB"pure_quanta"
LOCATION"R399"
$SEC"1"
CDS_SEC"1";
"B"
$PN"2"27;
"A"
$PN"1"21;
%"UNIVERSAL_GND"
"1","(-5225,925)","0","logical_power","I57";
;
CDS_LIB"logical_power"
HDL_POWER"GND";
"A"17;
%"Q_CAP"
"1","(-5225,1125)","0","pure_quanta","I58";
;
PACK_TYPE"0402"
TOLERANCE"10%"
VALUE"0.1UF"
PART_NUMBER"CH4104K1B00"
MATERIAL"X7R"
VOLTAGE"25V"
CDS_LIB"pure_quanta"
$LOCATION"C280"
CDS_LOCATION"C280"
$SEC"1"
CDS_SEC"1";
"B"
$PN"2"17;
"A"
$PN"1"9;
%"UNIVERSAL_GND"
"1","(-3800,2350)","0","logical_power","I61";
;
CDS_LIB"logical_power"
HDL_POWER"GND";
"A"18;
%"UNIVERSAL_GND"
"1","(-3450,3050)","0","logical_power","I63";
;
HDL_POWER"GND"
CDS_LIB"logical_power";
"A"19;
%"Q_CAP"
"1","(-3450,3250)","2","pure_quanta","I64";
;
MATERIAL"X7R"
PACK_TYPE"0402"
VALUE"0.1UF"
PART_NUMBER"CH4104K1B00"
TOLERANCE"10%"
VOLTAGE"25V"
CDS_LIB"pure_quanta"
$LOCATION"C302"
CDS_LOCATION"C302"
$SEC"1"
CDS_SEC"1";
"B"
$PN"2"19;
"A"
$PN"1"4;
%"74LVC1G08GW"
"1","(-3750,2775)","0","pure_quanta","I66";
;
PACK_TYPE"SM"
VALUE"74LVC1G08GW"
PART_NUMBER"ALVC1G08009"
MATERIAL"IC"
NEEDS_NO_SIZE"TRUE"
CDS_LIB"pure_quanta"
$LOCATION"U53"
CDS_LOCATION"U53"
$SEC"1"
CDS_SEC"1";
"VCC"
$PN"5"4;
"Y"
$PN"4"26;
"B"
$PN"1"25;
"A"
$PN"2"24;
"GND"
$PN"3"18;
%"Q_CAP"
"1","(-4025,-500)","0","pure_quanta","I7";
;
MATERIAL"X6S"
VALUE"1UF"
TOLERANCE"10%"
VOLTAGE"25V"
PACK_TYPE"C0402"
PART_NUMBER"CH5104KEB02"
CDS_LIB"pure_quanta"
SEC_TYPE"C0402"
LOCATION"PC260"
SEC"1";
"B"
$PN"2"12;
"A"
$PN"1"30;
%"Q_RES"
"2","(-2950,-850)","0","pure_quanta","I71";
;
VALUE"100K"
TOLERANCE"1%"
WATTAGE"1/16W"
PACK_TYPE"0402LF"
MATERIAL"CHIP"
PART_NUMBER"CS41002FB09"
CDS_LIB"pure_quanta"
LOCATION"PR543"
$SEC"1"
CDS_SEC"1";
"A"
$PN"1"32;
"B"
$PN"2"11;
%"Q_RES"
"1","(-3650,550)","0","pure_quanta","I72";
;
MATERIAL"EMPTY"
PART_NUMBER"CS00002JB13"
TOLERANCE"5%"
VALUE"0"
WATTAGE"1/16W"
PACK_TYPE"0402LF"
CDS_LIB"pure_quanta"
$LOCATION"R878"
CDS_LOCATION"R878"
$SEC"1"
CDS_SEC"1";
"B"
$PN"2"27;
"A"
$PN"1"22;
%"UNIVERSAL_POWER"
"1","(-3450,3450)","0","logical_power","I74";
;
HDL_POWER"P3V3_LDO"
CDS_LIB"logical_power";
"A"4;
%"Q_RES"
"2","(-4025,-75)","0","pure_quanta","I8";
;
PART_NUMBER"CS-5102JB02"
PACK_TYPE"0402LF"
MATERIAL"CHIP"
WATTAGE"1/16W"
TOLERANCE"5%"
VALUE"5.1"
CDS_LIB"pure_quanta"
LOCATION"PR541"
$SEC"1"
CDS_SEC"1";
"A"
$PN"1"3;
"B"
$PN"2"30;
%"VCCAUX15"
"1","(-4025,150)","0","logical_power","I9";
;
HDL_POWER"PVCC2_AUX"
CDS_LIB"logical_power";
"A"3;
END.
